# BASEBOARD_FAB2 (Tioga Pass) — schematic netlist excerpt (pin names and nets, part order shuffled) for the footprints in the layout excerpt that follows; sources: Cadence DE-HDL packaged netlist, KiCad conversion of Wiwynn_Tioga_Pass_MB.brd

C7D1  CAP_A  0.1UF 16V 10% X7R  pkg 0402V  page 118 : A = P3V3_STBY ; B = GND
R25W4  120R2F-GP  1%  pkg RCL_GP  page 151 : \1\ = GND ; \2\ = BMC_M_MALERT_N
R9F24  RES  0.0 5% EMPTY  pkg 0402  page 158 : A = SPA_MID_DBG_RX ; B = SP2_BMC_CM_UART_RX

(kicad_pcb
	(version 20260206)
	(generator "pcbnew")
	(generator_version "10.0")
	(general
		(thickness 1.6)
		(legacy_teardrops no)
	)
	(paper "A4")
	(title_block
		(title "Wiwynn_Tioga_Pass_MB.brd")
		(comment 1 "Tioga Pass / footprints 356-358 of 4770")
	)
	(layers
		(0 "F.Cu" signal "TOP")
		(4 "In1.Cu" signal "L2GND")
		(6 "In2.Cu" signal "L3")
		(8 "In3.Cu" signal "L4GND")
		(10 "In4.Cu" signal "L5")
		(12 "In5.Cu" signal "L6GND")
		(14 "In6.Cu" signal "L7VCC")
		(16 "In7.Cu" signal "L8VCC")
		(18 "In8.Cu" signal "L9GND")
		(20 "In9.Cu" signal "L10")
		(22 "In10.Cu" signal "L11GND")
		(24 "In11.Cu" signal "L12")
		(26 "In12.Cu" signal "L13GND")
		(2 "B.Cu" signal "BOTTOM")
		(9 "F.Adhes" user "F.Adhesive")
		(11 "B.Adhes" user "B.Adhesive")
		(13 "F.Paste" user "Package Geometry/Pastemask Top")
		(15 "B.Paste" user "Package Geometry/Pastemask Bottom")
		(5 "F.SilkS" user "Ref Des/Silkscreen Top")
		(7 "B.SilkS" user "Ref Des/Silkscreen Bottom")
		(1 "F.Mask" user "Board Geometry/Soldermask Top")
		(3 "B.Mask" user "Board Geometry/Soldermask Bottom")
		(17 "Dwgs.User" user "User.Drawings")
		(19 "Cmts.User" user "User.Comments")
		(21 "Eco1.User" user "User.Eco1")
		(23 "Eco2.User" user "User.Eco2")
		(25 "Edge.Cuts" user "Board Geometry/Outline")
		(27 "Margin" user)
		(31 "F.CrtYd" user "Package Geometry/Place Bound Top")
		(29 "B.CrtYd" user "Package Geometry/Place Bound Bottom")
		(35 "F.Fab" user "Ref Des/Assembly Top")
		(33 "B.Fab" user "Ref Des/Assembly Bottom")
	)
	(footprint ""
		(layer "F.Cu")
		(at 366.2172 -92.1766 180)
		(property "Reference" "C7D1"
			(at 0 0 180)
			(layer "F.SilkS")
			(hide yes)
			(effects
				(font
					(size 1.27 1.27)
				)
			)
		)
		(property "Value" ""
			(at 0 0 180)
			(layer "F.Fab")
			(effects
				(font
					(size 1.27 1.27)
				)
			)
		)
		(duplicate_pad_numbers_are_jumpers no)
		(fp_poly
			(pts
				(xy 0.3048 -0.1016) (xy 0.3048 0.9906) (xy -0.3048 0.9906) (xy -0.3048 -0.1016)
			)
			(stroke
				(width 0)
				(type default)
			)
			(fill no)
			(layer "F.CrtYd")
		)
		(fp_line
			(start 0.3048 0.9906)
			(end 0.3048 -0.1016)
			(stroke
				(width 0.1)
				(type default)
			)
			(layer "F.Fab")
		)
		(fp_line
			(start 0.3048 -0.1016)
			(end -0.3048 -0.1016)
			(stroke
				(width 0.1)
				(type default)
			)
			(layer "F.Fab")
		)
		(fp_line
			(start -0.3048 0.9906)
			(end 0.3048 0.9906)
			(stroke
				(width 0.1)
				(type default)
			)
			(layer "F.Fab")
		)
		(fp_line
			(start -0.3048 -0.1016)
			(end -0.3048 0.9906)
			(stroke
				(width 0.1)
				(type default)
			)
			(layer "F.Fab")
		)
		(pad "1" smd rect
			(at 0 0 180)
			(size 0.508 0.508)
			(layers "F.Cu" "F.Mask" "F.Paste")
			(net "P3V3_STBY")
		)
		(pad "2" smd rect
			(at 0 0.889 180)
			(size 0.508 0.508)
			(layers "F.Cu" "F.Mask" "F.Paste")
			(net "GND")
		)
		(zone
			(layer "F.Cu")
			(hatch none 0.5)
			(connect_pads
				(clearance 0)
			)
			(min_thickness 0.25)
			(keepout
				(tracks not_allowed)
				(vias allowed)
				(pads allowed)
				(copperpour not_allowed)
				(footprints allowed)
			)
			(placement
				(enabled no)
				(sheetname "")
			)
			(fill
				(thermal_gap 0.5)
				(thermal_bridge_width 0.5)
				(island_removal_mode 0)
			)
			(polygon
				(pts
					(xy 366.4712 -92.8116) (xy 365.9632 -92.8116) (xy 365.9632 -92.4306) (xy 366.4712 -92.4306)
				)
			)
		)
		(zone
			(layer "F.Cu")
			(hatch none 0.5)
			(connect_pads
				(clearance 0)
			)
			(min_thickness 0.25)
			(keepout
				(tracks allowed)
				(vias not_allowed)
				(pads allowed)
				(copperpour not_allowed)
				(footprints allowed)
			)
			(placement
				(enabled no)
				(sheetname "")
			)
			(fill
				(thermal_gap 0.5)
				(thermal_bridge_width 0.5)
				(island_removal_mode 0)
			)
			(polygon
				(pts
					(xy 366.4712 -92.4306) (xy 365.9632 -92.4306) (xy 365.9632 -92.8116) (xy 366.4712 -92.8116)
				)
			)
		)
	)
	(footprint ""
		(layer "F.Cu")
		(at 435.404006 -41.663874 180)
		(property "Reference" "R25W4"
			(at 0 0 180)
			(layer "F.SilkS")
			(hide yes)
			(effects
				(font
					(size 1.27 1.27)
				)
			)
		)
		(property "Value" "*"
			(at 0.064008 -4.108196 180)
			(unlocked yes)
			(layer "F.Fab")
			(hide yes)
			(effects
				(font
					(size 1.27 1.016)
					(thickness 0.1524)
				)
			)
		)
		(property "Device Type" "120R2F-GP_RCL_GP-120R2F-GP,64.A"
			(at 0.064008 -5.632196 180)
			(unlocked yes)
			(layer "F.Fab")
			(hide yes)
			(effects
				(font
					(size 1.27 1.016)
					(thickness 0.1524)
				)
			)
		)
		(duplicate_pad_numbers_are_jumpers no)
		(fp_line
			(start 0.508 -0.9398)
			(end -0.508 -0.9398)
			(stroke
				(width 0.1524)
				(type default)
			)
			(layer "F.SilkS")
		)
		(fp_line
			(start -0.508 -0.9398)
			(end -0.508 0.9398)
			(stroke
				(width 0.1524)
				(type default)
			)
			(layer "F.SilkS")
		)
		(fp_rect
			(start -0.508 0.9398)
			(end 0.508 -0.9398)
			(stroke
				(width 0)
				(type default)
			)
			(fill no)
			(layer "F.CrtYd")
		)
		(fp_rect
			(start -0.508 0.9398)
			(end 0.508 -0.9398)
			(stroke
				(width 0)
				(type default)
			)
			(fill no)
			(layer "F.Fab")
		)
		(pad "1" smd custom
			(at 0 -0.4445 180)
			(size 0.1397 0.1397)
			(layers "F.Cu" "F.Mask" "F.Paste")
			(net "GND")
			(options
				(clearance outline)
				(anchor circle)
			)
			(primitives
				(gr_poly
					(pts
						(arc
							(start -0.1778 -0.2794)
							(mid -0.249642 -0.249642)
							(end -0.2794 -0.1778)
						)
						(arc
							(start -0.2794 0.1778)
							(mid -0.249642 0.249642)
							(end -0.1778 0.2794)
						)
						(arc
							(start 0.1778 0.2794)
							(mid 0.249642 0.249642)
							(end 0.2794 0.1778)
						)
						(arc
							(start 0.2794 -0.1778)
							(mid 0.249642 -0.249642)
							(end 0.1778 -0.2794)
						)
					)
					(width 0)
					(fill yes)
				)
			)
		)
		(pad "2" smd custom
			(at 0 0.4445 180)
			(size 0.1397 0.1397)
			(layers "F.Cu" "F.Mask" "F.Paste")
			(net "BMC_M_MALERT_N")
			(options
				(clearance outline)
				(anchor circle)
			)
			(primitives
				(gr_poly
					(pts
						(arc
							(start -0.1778 -0.2794)
							(mid -0.249642 -0.249642)
							(end -0.2794 -0.1778)
						)
						(arc
							(start -0.2794 0.1778)
							(mid -0.249642 0.249642)
							(end -0.1778 0.2794)
						)
						(arc
							(start 0.1778 0.2794)
							(mid 0.249642 0.249642)
							(end 0.2794 0.1778)
						)
						(arc
							(start 0.2794 -0.1778)
							(mid 0.249642 -0.249642)
							(end 0.1778 -0.2794)
						)
					)
					(width 0)
					(fill yes)
				)
			)
		)
	)
	(footprint ""
		(layer "F.Cu")
		(at 487.969306 -27.666696)
		(property "Reference" "R9F24"
			(at 0 0 0)
			(layer "F.SilkS")
			(hide yes)
			(effects
				(font
					(size 1.27 1.27)
				)
			)
		)
		(property "Value" ""
			(at 0 0 0)
			(layer "F.Fab")
			(effects
				(font
					(size 1.27 1.27)
				)
			)
		)
		(duplicate_pad_numbers_are_jumpers no)
		(fp_poly
			(pts
				(xy -0.2794 -0.1016) (xy 0.2794 -0.1016) (xy 0.2794 0.9906) (xy -0.2794 0.9906)
			)
			(stroke
				(width 0)
				(type default)
			)
			(fill no)
			(layer "F.CrtYd")
		)
		(fp_line
			(start -0.2794 -0.1016)
			(end -0.2794 0.9906)
			(stroke
				(width 0.1)
				(type default)
			)
			(layer "F.Fab")
		)
		(fp_line
			(start -0.2794 0.9906)
			(end 0.2794 0.9906)
			(stroke
				(width 0.1)
				(type default)
			)
			(layer "F.Fab")
		)
		(fp_line
			(start 0.2794 -0.1016)
			(end -0.2794 -0.1016)
			(stroke
				(width 0.1)
				(type default)
			)
			(layer "F.Fab")
		)
		(fp_line
			(start 0.2794 0.9906)
			(end 0.2794 -0.1016)
			(stroke
				(width 0.1)
				(type default)
			)
			(layer "F.Fab")
		)
		(pad "1" smd rect
			(at 0 0)
			(size 0.508 0.508)
			(layers "F.Cu" "F.Mask" "F.Paste")
			(net "SPA_MID_DBG_RX")
		)
		(pad "2" smd rect
			(at 0 0.889)
			(size 0.508 0.508)
			(layers "F.Cu" "F.Mask" "F.Paste")
			(net "SP2_BMC_CM_UART_RX")
		)
		(zone
			(layer "F.Cu")
			(hatch none 0.5)
			(connect_pads
				(clearance 0)
			)
			(min_thickness 0.25)
			(keepout
				(tracks allowed)
				(vias not_allowed)
				(pads allowed)
				(copperpour not_allowed)
				(footprints allowed)
			)
			(placement
				(enabled no)
				(sheetname "")
			)
			(fill
				(thermal_gap 0.5)
				(thermal_bridge_width 0.5)
				(island_removal_mode 0)
			)
			(polygon
				(pts
					(xy 487.715306 -27.412696) (xy 488.223306 -27.412696) (xy 488.223306 -27.031696) (xy 487.715306 -27.031696)
				)
			)
		)
		(zone
			(layer "F.Cu")
			(hatch none 0.5)
			(connect_pads
				(clearance 0)
			)
			(min_thickness 0.25)
			(keepout
				(tracks not_allowed)
				(vias allowed)
				(pads allowed)
				(copperpour not_allowed)
				(footprints allowed)
			)
			(placement
				(enabled no)
				(sheetname "")
			)
			(fill
				(thermal_gap 0.5)
				(thermal_bridge_width 0.5)
				(island_removal_mode 0)
			)
			(polygon
				(pts
					(xy 487.715306 -27.031696) (xy 488.223306 -27.031696) (xy 488.223306 -27.412696) (xy 487.715306 -27.412696)
				)
			)
		)
	)
)
